(kicad_pcb
	(version 20260206)
	(generator "pcbnew")
	(generator_version "10.0")
	(general
		(thickness 1.6)
		(legacy_teardrops no)
	)
	(paper "A4")
	(title_block
		(title "dpb — 14545-sa.0730WZS0815.brd")
		(comment 1 "Honey Badger (Wiwynn) / footprint 323 of 1066 (CN1), pads 1-93 of 166")
	)
	(layers
		(0 "F.Cu" signal "TOP")
		(4 "In1.Cu" signal "L2GND")
		(6 "In2.Cu" signal "L3")
		(8 "In3.Cu" signal "L4VCC")
		(10 "In4.Cu" signal "L5VCC")
		(12 "In5.Cu" signal "L6")
		(14 "In6.Cu" signal "L7GND")
		(2 "B.Cu" signal "BOTTOM")
		(9 "F.Adhes" user "F.Adhesive")
		(11 "B.Adhes" user "B.Adhesive")
		(13 "F.Paste" user "Package Geometry/Pastemask Top")
		(15 "B.Paste" user "Package Geometry/Pastemask Bottom")
		(5 "F.SilkS" user "Ref Des/Silkscreen Top")
		(7 "B.SilkS" user "Ref Des/Silkscreen Bottom")
		(1 "F.Mask" user "Board Geometry/Soldermask Top")
		(3 "B.Mask" user "Board Geometry/Soldermask Bottom")
		(17 "Dwgs.User" user "User.Drawings")
		(19 "Cmts.User" user "User.Comments")
		(21 "Eco1.User" user "User.Eco1")
		(23 "Eco2.User" user "User.Eco2")
		(25 "Edge.Cuts" user "Board Geometry/Outline")
		(27 "Margin" user)
		(31 "F.CrtYd" user "Package Geometry/Place Bound Top")
		(29 "B.CrtYd" user "Package Geometry/Place Bound Bottom")
		(35 "F.Fab" user "Ref Des/Assembly Top")
		(33 "B.Fab" user "Ref Des/Assembly Bottom")
	)
	(footprint ""
		(layer "F.Cu")
		(at 2.500122 -355.998526 -90)
		(property "Reference" "CN1"
			(at 0 0 270)
			(layer "F.SilkS")
			(hide yes)
			(effects
				(font
					(size 1.27 1.27)
				)
			)
		)
		(property "Value" "PCISLT164-70-GP"
			(at -77.8764 -6.4262 270)
			(unlocked yes)
			(layer "F.Fab")
			(hide yes)
			(effects
				(font
					(size 1.016 1.016)
					(thickness 0.1524)
				)
			)
		)
		(property "Device Type" "G630EAA12048EU"
			(at -77.8764 -7.9502 270)
			(unlocked yes)
			(layer "F.Fab")
			(hide yes)
			(effects
				(font
					(size 1.016 1.016)
					(thickness 0.1524)
				)
			)
		)
		(duplicate_pad_numbers_are_jumpers no)
		(pad "" np_thru_hole circle
			(at -76.300076 0 270)
			(size 0.254 0.254)
			(drill 2.3114)
			(layers "*.Cu" "*.Mask")
			(clearance 1.3843)
			(thermal_gap 1.3843)
		)
		(pad "" np_thru_hole circle
			(at 16.299942 0 270)
			(size 0.254 0.254)
			(drill 2.3114)
			(layers "*.Cu" "*.Mask")
			(clearance 1.3843)
			(thermal_gap 1.3843)
		)
		(pad "A1" smd rect
			(at 11.500104 -0.311404 270)
			(size 0.7112 3.6068)
			(drill
				(offset 0 -0.381)
			)
			(layers "F.Cu" "F.Mask" "F.Paste")
			(net "GND")
		)
		(pad "A2" smd rect
			(at 10.500106 -0.311404 270)
			(size 0.7112 3.6068)
			(drill
				(offset 0 -0.381)
			)
			(layers "F.Cu" "F.Mask" "F.Paste")
			(net "SAS2X28_A_HDD11_RX_+")
		)
		(pad "A3" smd rect
			(at 9.500108 -0.311404 270)
			(size 0.7112 3.6068)
			(drill
				(offset 0 -0.381)
			)
			(layers "F.Cu" "F.Mask" "F.Paste")
			(net "SAS2X28_A_HDD11_RX_-")
		)
		(pad "A4" smd rect
			(at 8.50011 -0.311404 270)
			(size 0.7112 3.6068)
			(drill
				(offset 0 -0.381)
			)
			(layers "F.Cu" "F.Mask" "F.Paste")
			(net "GND")
		)
		(pad "A5" smd rect
			(at 7.500112 -0.311404 270)
			(size 0.7112 3.6068)
			(drill
				(offset 0 -0.381)
			)
			(layers "F.Cu" "F.Mask" "F.Paste")
			(net "GND")
		)
		(pad "A6" smd rect
			(at 6.500114 -0.311404 270)
			(size 0.7112 3.6068)
			(drill
				(offset 0 -0.381)
			)
			(layers "F.Cu" "F.Mask" "F.Paste")
			(net "SAS2X28_A_HDD12_RX_+")
		)
		(pad "A7" smd rect
			(at 5.500116 -0.311404 270)
			(size 0.7112 3.6068)
			(drill
				(offset 0 -0.381)
			)
			(layers "F.Cu" "F.Mask" "F.Paste")
			(net "SAS2X28_A_HDD12_RX_-")
		)
		(pad "A8" smd rect
			(at 4.500118 -0.311404 270)
			(size 0.7112 3.6068)
			(drill
				(offset 0 -0.381)
			)
			(layers "F.Cu" "F.Mask" "F.Paste")
			(net "GND")
		)
		(pad "A9" smd rect
			(at 3.50012 -0.311404 270)
			(size 0.7112 3.6068)
			(drill
				(offset 0 -0.381)
			)
			(layers "F.Cu" "F.Mask" "F.Paste")
			(net "GND")
		)
		(pad "A10" smd rect
			(at 2.500122 -0.311404 270)
			(size 0.7112 3.6068)
			(drill
				(offset 0 -0.381)
			)
			(layers "F.Cu" "F.Mask" "F.Paste")
			(net "SAS2X28_A_HDD13_RX_+")
		)
		(pad "A11" smd rect
			(at 1.500124 -0.311404 270)
			(size 0.7112 3.6068)
			(drill
				(offset 0 -0.381)
			)
			(layers "F.Cu" "F.Mask" "F.Paste")
			(net "SAS2X28_A_HDD13_RX_-")
		)
		(pad "A12" smd rect
			(at -1.500124 -0.311404 270)
			(size 0.7112 3.6068)
			(drill
				(offset 0 -0.381)
			)
			(layers "F.Cu" "F.Mask" "F.Paste")
			(net "TRAY_ID")
		)
		(pad "A13" smd rect
			(at -2.500376 -0.311404 270)
			(size 0.7112 3.6068)
			(drill
				(offset 0 -0.381)
			)
			(layers "F.Cu" "F.Mask" "F.Paste")
			(net "GND")
		)
		(pad "A14" smd rect
			(at -3.500374 -0.311404 270)
			(size 0.7112 3.6068)
			(drill
				(offset 0 -0.381)
			)
			(layers "F.Cu" "F.Mask" "F.Paste")
			(net "SAS2X28_A_HDD14_RX_+")
		)
		(pad "A15" smd rect
			(at -4.500372 -0.311404 270)
			(size 0.7112 3.6068)
			(drill
				(offset 0 -0.381)
			)
			(layers "F.Cu" "F.Mask" "F.Paste")
			(net "SAS2X28_A_HDD14_RX_-")
		)
		(pad "A16" smd rect
			(at -5.50037 -0.311404 270)
			(size 0.7112 3.6068)
			(drill
				(offset 0 -0.381)
			)
			(layers "F.Cu" "F.Mask" "F.Paste")
			(net "GND")
		)
		(pad "A17" smd rect
			(at -6.500368 -0.311404 270)
			(size 0.7112 3.6068)
			(drill
				(offset 0 -0.381)
			)
			(layers "F.Cu" "F.Mask" "F.Paste")
			(net "GND")
		)
		(pad "A18" smd rect
			(at -7.500366 -0.311404 270)
			(size 0.7112 3.6068)
			(drill
				(offset 0 -0.381)
			)
			(layers "F.Cu" "F.Mask" "F.Paste")
			(net "SAS2X28_A_HDD9_RX_+")
		)
		(pad "A19" smd rect
			(at -8.500364 -0.311404 270)
			(size 0.7112 3.6068)
			(drill
				(offset 0 -0.381)
			)
			(layers "F.Cu" "F.Mask" "F.Paste")
			(net "SAS2X28_A_HDD9_RX_-")
		)
		(pad "A20" smd rect
			(at -9.500362 -0.311404 270)
			(size 0.7112 3.6068)
			(drill
				(offset 0 -0.381)
			)
			(layers "F.Cu" "F.Mask" "F.Paste")
			(net "GND")
		)
		(pad "A21" smd rect
			(at -10.50036 -0.311404 270)
			(size 0.7112 3.6068)
			(drill
				(offset 0 -0.381)
			)
			(layers "F.Cu" "F.Mask" "F.Paste")
			(net "GND")
		)
		(pad "A22" smd rect
			(at -11.500358 -0.311404 270)
			(size 0.7112 3.6068)
			(drill
				(offset 0 -0.381)
			)
			(layers "F.Cu" "F.Mask" "F.Paste")
			(net "SAS2X28_A_HDD8_RX_+")
		)
		(pad "A23" smd rect
			(at -12.500356 -0.311404 270)
			(size 0.7112 3.6068)
			(drill
				(offset 0 -0.381)
			)
			(layers "F.Cu" "F.Mask" "F.Paste")
			(net "SAS2X28_A_HDD8_RX_-")
		)
		(pad "A24" smd rect
			(at -13.500354 -0.311404 270)
			(size 0.7112 3.6068)
			(drill
				(offset 0 -0.381)
			)
			(layers "F.Cu" "F.Mask" "F.Paste")
			(net "GND")
		)
		(pad "A25" smd rect
			(at -14.500352 -0.311404 270)
			(size 0.7112 3.6068)
			(drill
				(offset 0 -0.381)
			)
			(layers "F.Cu" "F.Mask" "F.Paste")
			(net "GND")
		)
		(pad "A26" smd rect
			(at -15.50035 -0.311404 270)
			(size 0.7112 3.6068)
			(drill
				(offset 0 -0.381)
			)
			(layers "F.Cu" "F.Mask" "F.Paste")
			(net "SAS2X28_A_HDD7_RX_+")
		)
		(pad "A27" smd rect
			(at -16.500348 -0.311404 270)
			(size 0.7112 3.6068)
			(drill
				(offset 0 -0.381)
			)
			(layers "F.Cu" "F.Mask" "F.Paste")
			(net "SAS2X28_A_HDD7_RX_-")
		)
		(pad "A28" smd rect
			(at -17.500346 -0.311404 270)
			(size 0.7112 3.6068)
			(drill
				(offset 0 -0.381)
			)
			(layers "F.Cu" "F.Mask" "F.Paste")
			(net "GND")
		)
		(pad "A29" smd rect
			(at -18.500344 -0.311404 270)
			(size 0.7112 3.6068)
			(drill
				(offset 0 -0.381)
			)
			(layers "F.Cu" "F.Mask" "F.Paste")
			(net "GND")
		)
		(pad "A30" smd rect
			(at -19.500342 -0.311404 270)
			(size 0.7112 3.6068)
			(drill
				(offset 0 -0.381)
			)
			(layers "F.Cu" "F.Mask" "F.Paste")
			(net "SAS2X28_A_HDD4_RX_+")
		)
		(pad "A31" smd rect
			(at -20.50034 -0.311404 270)
			(size 0.7112 3.6068)
			(drill
				(offset 0 -0.381)
			)
			(layers "F.Cu" "F.Mask" "F.Paste")
			(net "SAS2X28_A_HDD4_RX_-")
		)
		(pad "A32" smd rect
			(at -21.500338 -0.311404 270)
			(size 0.7112 3.6068)
			(drill
				(offset 0 -0.381)
			)
			(layers "F.Cu" "F.Mask" "F.Paste")
			(net "GND")
		)
		(pad "A33" smd rect
			(at -22.500336 -0.311404 270)
			(size 0.7112 3.6068)
			(drill
				(offset 0 -0.381)
			)
			(layers "F.Cu" "F.Mask" "F.Paste")
			(net "GND")
		)
		(pad "A34" smd rect
			(at -23.500334 -0.311404 270)
			(size 0.7112 3.6068)
			(drill
				(offset 0 -0.381)
			)
			(layers "F.Cu" "F.Mask" "F.Paste")
			(net "SAS2X28_A_HDD3_RX_+")
		)
		(pad "A35" smd rect
			(at -24.500332 -0.311404 270)
			(size 0.7112 3.6068)
			(drill
				(offset 0 -0.381)
			)
			(layers "F.Cu" "F.Mask" "F.Paste")
			(net "SAS2X28_A_HDD3_RX_-")
		)
		(pad "A36" smd rect
			(at -25.50033 -0.311404 270)
			(size 0.7112 3.6068)
			(drill
				(offset 0 -0.381)
			)
			(layers "F.Cu" "F.Mask" "F.Paste")
			(net "GND")
		)
		(pad "A37" smd rect
			(at -26.500328 -0.311404 270)
			(size 0.7112 3.6068)
			(drill
				(offset 0 -0.381)
			)
			(layers "F.Cu" "F.Mask" "F.Paste")
			(net "GND")
		)
		(pad "A38" smd rect
			(at -27.500326 -0.311404 270)
			(size 0.7112 3.6068)
			(drill
				(offset 0 -0.381)
			)
			(layers "F.Cu" "F.Mask" "F.Paste")
			(net "SAS2X28_A_HDD6_RX_+")
		)
		(pad "A39" smd rect
			(at -28.500324 -0.311404 270)
			(size 0.7112 3.6068)
			(drill
				(offset 0 -0.381)
			)
			(layers "F.Cu" "F.Mask" "F.Paste")
			(net "SAS2X28_A_HDD6_RX_-")
		)
		(pad "A40" smd rect
			(at -29.500322 -0.311404 270)
			(size 0.7112 3.6068)
			(drill
				(offset 0 -0.381)
			)
			(layers "F.Cu" "F.Mask" "F.Paste")
			(net "GND")
		)
		(pad "A41" smd rect
			(at -30.50032 -0.311404 270)
			(size 0.7112 3.6068)
			(drill
				(offset 0 -0.381)
			)
			(layers "F.Cu" "F.Mask" "F.Paste")
			(net "SD_LATCH_RELEASE")
		)
		(pad "A42" smd rect
			(at -31.500318 -0.311404 270)
			(size 0.7112 3.6068)
			(drill
				(offset 0 -0.381)
			)
			(layers "F.Cu" "F.Mask" "F.Paste")
			(net "SAS2X28_A_HDD12_FLT")
		)
		(pad "A43" smd rect
			(at -32.500316 -0.311404 270)
			(size 0.7112 3.6068)
			(drill
				(offset 0 -0.381)
			)
			(layers "F.Cu" "F.Mask" "F.Paste")
			(net "SAS2X28_A_HDD11_FLT")
		)
		(pad "A44" smd rect
			(at -33.500314 -0.311404 270)
			(size 0.7112 3.6068)
			(drill
				(offset 0 -0.381)
			)
			(layers "F.Cu" "F.Mask" "F.Paste")
			(net "SAS2X28_A_HDD13_FLT")
		)
		(pad "A45" smd rect
			(at -34.500312 -0.311404 270)
			(size 0.7112 3.6068)
			(drill
				(offset 0 -0.381)
			)
			(layers "F.Cu" "F.Mask" "F.Paste")
			(net "SAS2X28_A_HDD14_FLT")
		)
		(pad "A46" smd rect
			(at -35.50031 -0.311404 270)
			(size 0.7112 3.6068)
			(drill
				(offset 0 -0.381)
			)
			(layers "F.Cu" "F.Mask" "F.Paste")
			(net "SAS2X28_A_HDD9_FLT")
		)
		(pad "A47" smd rect
			(at -36.500308 -0.311404 270)
			(size 0.7112 3.6068)
			(drill
				(offset 0 -0.381)
			)
			(layers "F.Cu" "F.Mask" "F.Paste")
			(net "SAS2X28_A_HDD8_FLT")
		)
		(pad "A48" smd rect
			(at -37.500306 -0.311404 270)
			(size 0.7112 3.6068)
			(drill
				(offset 0 -0.381)
			)
			(layers "F.Cu" "F.Mask" "F.Paste")
			(net "SAS2X28_A_HDD7_FLT")
		)
		(pad "A49" smd rect
			(at -38.500304 -0.311404 270)
			(size 0.7112 3.6068)
			(drill
				(offset 0 -0.381)
			)
			(layers "F.Cu" "F.Mask" "F.Paste")
			(net "SAS2X28_A_HDD4_FLT")
		)
		(pad "A50" smd rect
			(at -39.500302 -0.311404 270)
			(size 0.7112 3.6068)
			(drill
				(offset 0 -0.381)
			)
			(layers "F.Cu" "F.Mask" "F.Paste")
			(net "SAS2X28_A_HDD3_FLT")
		)
		(pad "A51" smd rect
			(at -40.5003 -0.311404 270)
			(size 0.7112 3.6068)
			(drill
				(offset 0 -0.381)
			)
			(layers "F.Cu" "F.Mask" "F.Paste")
			(net "GND")
		)
		(pad "A52" smd rect
			(at -41.500298 -0.311404 270)
			(size 0.7112 3.6068)
			(drill
				(offset 0 -0.381)
			)
			(layers "F.Cu" "F.Mask" "F.Paste")
			(net "SAS2X28_A_HDD2_RX_+")
		)
		(pad "A53" smd rect
			(at -42.500296 -0.311404 270)
			(size 0.7112 3.6068)
			(drill
				(offset 0 -0.381)
			)
			(layers "F.Cu" "F.Mask" "F.Paste")
			(net "SAS2X28_A_HDD2_RX_-")
		)
		(pad "A54" smd rect
			(at -43.500294 -0.311404 270)
			(size 0.7112 3.6068)
			(drill
				(offset 0 -0.381)
			)
			(layers "F.Cu" "F.Mask" "F.Paste")
			(net "GND")
		)
		(pad "A55" smd rect
			(at -44.500292 -0.311404 270)
			(size 0.7112 3.6068)
			(drill
				(offset 0 -0.381)
			)
			(layers "F.Cu" "F.Mask" "F.Paste")
			(net "I2C_C_SCL_DAMP_A")
		)
		(pad "A56" smd rect
			(at -45.50029 -0.311404 270)
			(size 0.7112 3.6068)
			(drill
				(offset 0 -0.381)
			)
			(layers "F.Cu" "F.Mask" "F.Paste")
			(net "I2C_C_SDA_DAMP_A")
		)
		(pad "A57" smd rect
			(at -46.500288 -0.311404 270)
			(size 0.7112 3.6068)
			(drill
				(offset 0 -0.381)
			)
			(layers "F.Cu" "F.Mask" "F.Paste")
			(net "I2C_D_SCL_DAMP_A")
		)
		(pad "A58" smd rect
			(at -47.500286 -0.311404 270)
			(size 0.7112 3.6068)
			(drill
				(offset 0 -0.381)
			)
			(layers "F.Cu" "F.Mask" "F.Paste")
			(net "I2C_D_SDA_DAMP_A")
		)
		(pad "A59" smd rect
			(at -48.500284 -0.311404 270)
			(size 0.7112 3.6068)
			(drill
				(offset 0 -0.381)
			)
			(layers "F.Cu" "F.Mask" "F.Paste")
			(net "GND")
		)
		(pad "A60" smd rect
			(at -49.500282 -0.311404 270)
			(size 0.7112 3.6068)
			(drill
				(offset 0 -0.381)
			)
			(layers "F.Cu" "F.Mask" "F.Paste")
			(net "SAS2X28_A_HDD1_RX_+")
		)
		(pad "A61" smd rect
			(at -50.50028 -0.311404 270)
			(size 0.7112 3.6068)
			(drill
				(offset 0 -0.381)
			)
			(layers "F.Cu" "F.Mask" "F.Paste")
			(net "SAS2X28_A_HDD1_RX_-")
		)
		(pad "A62" smd rect
			(at -51.500278 -0.311404 270)
			(size 0.7112 3.6068)
			(drill
				(offset 0 -0.381)
			)
			(layers "F.Cu" "F.Mask" "F.Paste")
			(net "GND")
		)
		(pad "A63" smd rect
			(at -52.500276 -0.311404 270)
			(size 0.7112 3.6068)
			(drill
				(offset 0 -0.381)
			)
			(layers "F.Cu" "F.Mask" "F.Paste")
			(net "GND")
		)
		(pad "A64" smd rect
			(at -53.500274 -0.311404 270)
			(size 0.7112 3.6068)
			(drill
				(offset 0 -0.381)
			)
			(layers "F.Cu" "F.Mask" "F.Paste")
			(net "SAS2X28_A_HDD10_RX_+")
		)
		(pad "A65" smd rect
			(at -54.500272 -0.311404 270)
			(size 0.7112 3.6068)
			(drill
				(offset 0 -0.381)
			)
			(layers "F.Cu" "F.Mask" "F.Paste")
			(net "SAS2X28_A_HDD10_RX_-")
		)
		(pad "A66" smd rect
			(at -55.50027 -0.311404 270)
			(size 0.7112 3.6068)
			(drill
				(offset 0 -0.381)
			)
			(layers "F.Cu" "F.Mask" "F.Paste")
			(net "GND")
		)
		(pad "A67" smd rect
			(at -56.500268 -0.311404 270)
			(size 0.7112 3.6068)
			(drill
				(offset 0 -0.381)
			)
			(layers "F.Cu" "F.Mask" "F.Paste")
			(net "GND")
		)
		(pad "A68" smd rect
			(at -57.500266 -0.311404 270)
			(size 0.7112 3.6068)
			(drill
				(offset 0 -0.381)
			)
			(layers "F.Cu" "F.Mask" "F.Paste")
			(net "SAS2X28_A_HDD0_RX_+")
		)
		(pad "A69" smd rect
			(at -58.500264 -0.311404 270)
			(size 0.7112 3.6068)
			(drill
				(offset 0 -0.381)
			)
			(layers "F.Cu" "F.Mask" "F.Paste")
			(net "SAS2X28_A_HDD0_RX_-")
		)
		(pad "A70" smd rect
			(at -59.500262 -0.311404 270)
			(size 0.7112 3.6068)
			(drill
				(offset 0 -0.381)
			)
			(layers "F.Cu" "F.Mask" "F.Paste")
			(net "GND")
		)
		(pad "A71" smd rect
			(at -60.50026 -0.311404 270)
			(size 0.7112 3.6068)
			(drill
				(offset 0 -0.381)
			)
			(layers "F.Cu" "F.Mask" "F.Paste")
			(net "GND")
		)
		(pad "A72" smd rect
			(at -61.500258 -0.311404 270)
			(size 0.7112 3.6068)
			(drill
				(offset 0 -0.381)
			)
			(layers "F.Cu" "F.Mask" "F.Paste")
			(net "SAS2X28_A_HDD5_RX_+")
		)
		(pad "A73" smd rect
			(at -62.500256 -0.311404 270)
			(size 0.7112 3.6068)
			(drill
				(offset 0 -0.381)
			)
			(layers "F.Cu" "F.Mask" "F.Paste")
			(net "SAS2X28_A_HDD5_RX_-")
		)
		(pad "A74" smd rect
			(at -63.500254 -0.311404 270)
			(size 0.7112 3.6068)
			(drill
				(offset 0 -0.381)
			)
			(layers "F.Cu" "F.Mask" "F.Paste")
			(net "GND")
		)
		(pad "A75" smd rect
			(at -64.500252 -0.311404 270)
			(size 0.7112 3.6068)
			(drill
				(offset 0 -0.381)
			)
			(layers "F.Cu" "F.Mask" "F.Paste")
			(net "GND")
		)
		(pad "A76" smd rect
			(at -65.50025 -0.311404 270)
			(size 0.7112 3.6068)
			(drill
				(offset 0 -0.381)
			)
			(layers "F.Cu" "F.Mask" "F.Paste")
			(net "SEB_BA_RX+")
		)
		(pad "A77" smd rect
			(at -66.500248 -0.311404 270)
			(size 0.7112 3.6068)
			(drill
				(offset 0 -0.381)
			)
			(layers "F.Cu" "F.Mask" "F.Paste")
			(net "SEB_BA_RX-")
		)
		(pad "A78" smd rect
			(at -67.500246 -0.311404 270)
			(size 0.7112 3.6068)
			(drill
				(offset 0 -0.381)
			)
			(layers "F.Cu" "F.Mask" "F.Paste")
			(net "GND")
		)
		(pad "A79" smd rect
			(at -68.500244 -0.311404 270)
			(size 0.7112 3.6068)
			(drill
				(offset 0 -0.381)
			)
			(layers "F.Cu" "F.Mask" "F.Paste")
			(net "PEER_1B&2B_HB")
		)
		(pad "A80" smd rect
			(at -69.500242 -0.311404 270)
			(size 0.7112 3.6068)
			(drill
				(offset 0 -0.381)
			)
			(layers "F.Cu" "F.Mask" "F.Paste")
			(net "P12V")
		)
		(pad "A81" smd rect
			(at -70.50024 -0.311404 270)
			(size 0.7112 3.6068)
			(drill
				(offset 0 -0.381)
			)
			(layers "F.Cu" "F.Mask" "F.Paste")
			(net "P12V")
		)
		(pad "A82" smd rect
			(at -71.500238 -0.311404 270)
			(size 0.7112 3.6068)
			(drill
				(offset 0 -0.381)
			)
			(layers "F.Cu" "F.Mask" "F.Paste")
			(net "P12V")
		)
		(pad "B1" smd rect
			(at 11.500104 -0.692404 270)
			(size 0.7112 3.6068)
			(layers "F.Cu" "F.Mask" "F.Paste")
			(net "SAS2X28_A_PRSNT15")
		)
		(pad "B2" smd rect
			(at 10.500106 -0.692404 270)
			(size 0.7112 3.6068)
			(layers "F.Cu" "F.Mask" "F.Paste")
			(net "FCB_HW_REV")
		)
		(pad "B3" smd rect
			(at 9.500108 -0.692404 270)
			(size 0.7112 3.6068)
			(layers "F.Cu" "F.Mask" "F.Paste")
			(net "GND")
		)
		(pad "B4" smd rect
			(at 8.50011 -0.692404 270)
			(size 0.7112 3.6068)
			(layers "F.Cu" "F.Mask" "F.Paste")
			(net "SAS2X28_A_HDD11_TX_+")
		)
		(pad "B5" smd rect
			(at 7.500112 -0.692404 270)
			(size 0.7112 3.6068)
			(layers "F.Cu" "F.Mask" "F.Paste")
			(net "SAS2X28_A_HDD11_TX_-")
		)
		(pad "B6" smd rect
			(at 6.500114 -0.692404 270)
			(size 0.7112 3.6068)
			(layers "F.Cu" "F.Mask" "F.Paste")
			(net "GND")
		)
		(pad "B7" smd rect
			(at 5.500116 -0.692404 270)
			(size 0.7112 3.6068)
			(layers "F.Cu" "F.Mask" "F.Paste")
			(net "GND")
		)
		(pad "B8" smd rect
			(at 4.500118 -0.692404 270)
			(size 0.7112 3.6068)
			(layers "F.Cu" "F.Mask" "F.Paste")
			(net "SAS2X28_A_HDD12_TX_+")
		)
		(pad "B9" smd rect
			(at 3.50012 -0.692404 270)
			(size 0.7112 3.6068)
			(layers "F.Cu" "F.Mask" "F.Paste")
			(net "SAS2X28_A_HDD12_TX_-")
		)
	)
)
